# BASEBOARD_FAB2 (Tioga Pass) — schematic netlist excerpt (pin names and nets, part order shuffled) for the footprints in the layout excerpt that follows; sources: Cadence DE-HDL packaged netlist, KiCad conversion of Wiwynn_Tioga_Pass_MB.brd

R7W20  RES  4.75K 1% CHIP  pkg 0402  page 120 : A = P3V3_STBY ; B = FM_POST_CARD_PRES_BMC_R1_N
R6W49  RES  40.2K 1% CHIP  pkg 0402  page 168 : A = FM_UART_SWITCH_N ; B = FM_UART_SEL_N
R25W111  RES  4.75K 1% EMPTY  pkg 0402  page 150 : A = P3V3_STBY ; B = RMII_BMC_PCH_SPRNGVLLE_TXEN

(kicad_pcb
	(version 20260206)
	(generator "pcbnew")
	(generator_version "10.0")
	(general
		(thickness 1.6)
		(legacy_teardrops no)
	)
	(paper "A4")
	(title_block
		(title "Wiwynn_Tioga_Pass_MB.brd")
		(comment 1 "Tioga Pass / footprints 4185-4187 of 4770")
	)
	(layers
		(0 "F.Cu" signal "TOP")
		(4 "In1.Cu" signal "L2GND")
		(6 "In2.Cu" signal "L3")
		(8 "In3.Cu" signal "L4GND")
		(10 "In4.Cu" signal "L5")
		(12 "In5.Cu" signal "L6GND")
		(14 "In6.Cu" signal "L7VCC")
		(16 "In7.Cu" signal "L8VCC")
		(18 "In8.Cu" signal "L9GND")
		(20 "In9.Cu" signal "L10")
		(22 "In10.Cu" signal "L11GND")
		(24 "In11.Cu" signal "L12")
		(26 "In12.Cu" signal "L13GND")
		(2 "B.Cu" signal "BOTTOM")
		(9 "F.Adhes" user "F.Adhesive")
		(11 "B.Adhes" user "B.Adhesive")
		(13 "F.Paste" user "Package Geometry/Pastemask Top")
		(15 "B.Paste" user "Package Geometry/Pastemask Bottom")
		(5 "F.SilkS" user "Ref Des/Silkscreen Top")
		(7 "B.SilkS" user "Ref Des/Silkscreen Bottom")
		(1 "F.Mask" user "Board Geometry/Soldermask Top")
		(3 "B.Mask" user "Board Geometry/Soldermask Bottom")
		(17 "Dwgs.User" user "User.Drawings")
		(19 "Cmts.User" user "User.Comments")
		(21 "Eco1.User" user "User.Eco1")
		(23 "Eco2.User" user "User.Eco2")
		(25 "Edge.Cuts" user "Board Geometry/Outline")
		(27 "Margin" user)
		(31 "F.CrtYd" user "Package Geometry/Place Bound Top")
		(29 "B.CrtYd" user "Package Geometry/Place Bound Bottom")
		(35 "F.Fab" user "Ref Des/Assembly Top")
		(33 "B.Fab" user "Ref Des/Assembly Bottom")
	)
	(footprint ""
		(layer "B.Cu")
		(at 406.908 -23.0505)
		(property "Reference" "R25W111"
			(at 0.8382 -0.67818 0)
			(unlocked yes)
			(layer "B.SilkS")
			(effects
				(font
					(size 0.4064 0.254)
					(thickness 0.1524)
				)
				(justify left mirror)
			)
		)
		(property "Value" ""
			(at 0 0 0)
			(layer "B.Fab")
			(effects
				(font
					(size 1.27 1.27)
				)
				(justify mirror)
			)
		)
		(duplicate_pad_numbers_are_jumpers no)
		(fp_poly
			(pts
				(xy 0.2794 -0.1016) (xy -0.2794 -0.1016) (xy -0.2794 0.9906) (xy 0.2794 0.9906)
			)
			(stroke
				(width 0)
				(type default)
			)
			(fill no)
			(layer "B.CrtYd")
		)
		(fp_line
			(start -0.2794 -0.1016)
			(end 0.2794 -0.1016)
			(stroke
				(width 0.1)
				(type default)
			)
			(layer "B.Fab")
		)
		(fp_line
			(start -0.2794 0.9906)
			(end -0.2794 -0.1016)
			(stroke
				(width 0.1)
				(type default)
			)
			(layer "B.Fab")
		)
		(fp_line
			(start 0.2794 -0.1016)
			(end 0.2794 0.9906)
			(stroke
				(width 0.1)
				(type default)
			)
			(layer "B.Fab")
		)
		(fp_line
			(start 0.2794 0.9906)
			(end -0.2794 0.9906)
			(stroke
				(width 0.1)
				(type default)
			)
			(layer "B.Fab")
		)
		(pad "1" smd rect
			(at 0 0 180)
			(size 0.508 0.508)
			(layers "B.Cu" "B.Mask" "B.Paste")
			(net "P3V3_STBY")
		)
		(pad "2" smd rect
			(at 0 0.889 180)
			(size 0.508 0.508)
			(layers "B.Cu" "B.Mask" "B.Paste")
			(net "RMII_BMC_PCH_SPRNGVLLE_TXEN")
		)
		(zone
			(layer "B.Cu")
			(hatch none 0.5)
			(connect_pads
				(clearance 0)
			)
			(min_thickness 0.25)
			(keepout
				(tracks allowed)
				(vias not_allowed)
				(pads allowed)
				(copperpour not_allowed)
				(footprints allowed)
			)
			(placement
				(enabled no)
				(sheetname "")
			)
			(fill
				(thermal_gap 0.5)
				(thermal_bridge_width 0.5)
				(island_removal_mode 0)
			)
			(polygon
				(pts
					(xy 407.162 -22.7965) (xy 406.654 -22.7965) (xy 406.654 -22.4155) (xy 407.162 -22.4155)
				)
			)
		)
		(zone
			(layer "B.Cu")
			(hatch none 0.5)
			(connect_pads
				(clearance 0)
			)
			(min_thickness 0.25)
			(keepout
				(tracks not_allowed)
				(vias allowed)
				(pads allowed)
				(copperpour not_allowed)
				(footprints allowed)
			)
			(placement
				(enabled no)
				(sheetname "")
			)
			(fill
				(thermal_gap 0.5)
				(thermal_bridge_width 0.5)
				(island_removal_mode 0)
			)
			(polygon
				(pts
					(xy 407.162 -22.4155) (xy 406.654 -22.4155) (xy 406.654 -22.7965) (xy 407.162 -22.7965)
				)
			)
		)
	)
	(footprint ""
		(layer "B.Cu")
		(at 482.4857 -148.93671)
		(property "Reference" "R6W49"
			(at 0.8382 -0.67818 0)
			(unlocked yes)
			(layer "B.SilkS")
			(effects
				(font
					(size 0.4064 0.254)
					(thickness 0.1524)
				)
				(justify left mirror)
			)
		)
		(property "Value" ""
			(at 0 0 0)
			(layer "B.Fab")
			(effects
				(font
					(size 1.27 1.27)
				)
				(justify mirror)
			)
		)
		(duplicate_pad_numbers_are_jumpers no)
		(fp_poly
			(pts
				(xy 0.2794 -0.1016) (xy -0.2794 -0.1016) (xy -0.2794 0.9906) (xy 0.2794 0.9906)
			)
			(stroke
				(width 0)
				(type default)
			)
			(fill no)
			(layer "B.CrtYd")
		)
		(fp_line
			(start -0.2794 -0.1016)
			(end 0.2794 -0.1016)
			(stroke
				(width 0.1)
				(type default)
			)
			(layer "B.Fab")
		)
		(fp_line
			(start -0.2794 0.9906)
			(end -0.2794 -0.1016)
			(stroke
				(width 0.1)
				(type default)
			)
			(layer "B.Fab")
		)
		(fp_line
			(start 0.2794 -0.1016)
			(end 0.2794 0.9906)
			(stroke
				(width 0.1)
				(type default)
			)
			(layer "B.Fab")
		)
		(fp_line
			(start 0.2794 0.9906)
			(end -0.2794 0.9906)
			(stroke
				(width 0.1)
				(type default)
			)
			(layer "B.Fab")
		)
		(pad "1" smd rect
			(at 0 0 180)
			(size 0.508 0.508)
			(layers "B.Cu" "B.Mask" "B.Paste")
			(net "FM_UART_SWITCH_N")
		)
		(pad "2" smd rect
			(at 0 0.889 180)
			(size 0.508 0.508)
			(layers "B.Cu" "B.Mask" "B.Paste")
			(net "FM_UART_SEL_N")
		)
		(zone
			(layer "B.Cu")
			(hatch none 0.5)
			(connect_pads
				(clearance 0)
			)
			(min_thickness 0.25)
			(keepout
				(tracks allowed)
				(vias not_allowed)
				(pads allowed)
				(copperpour not_allowed)
				(footprints allowed)
			)
			(placement
				(enabled no)
				(sheetname "")
			)
			(fill
				(thermal_gap 0.5)
				(thermal_bridge_width 0.5)
				(island_removal_mode 0)
			)
			(polygon
				(pts
					(xy 482.7397 -148.68271) (xy 482.2317 -148.68271) (xy 482.2317 -148.30171) (xy 482.7397 -148.30171)
				)
			)
		)
		(zone
			(layer "B.Cu")
			(hatch none 0.5)
			(connect_pads
				(clearance 0)
			)
			(min_thickness 0.25)
			(keepout
				(tracks not_allowed)
				(vias allowed)
				(pads allowed)
				(copperpour not_allowed)
				(footprints allowed)
			)
			(placement
				(enabled no)
				(sheetname "")
			)
			(fill
				(thermal_gap 0.5)
				(thermal_bridge_width 0.5)
				(island_removal_mode 0)
			)
			(polygon
				(pts
					(xy 482.7397 -148.30171) (xy 482.2317 -148.30171) (xy 482.2317 -148.68271) (xy 482.7397 -148.68271)
				)
			)
		)
	)
	(footprint ""
		(layer "B.Cu")
		(at 399.891758 -116.317014 180)
		(property "Reference" "R7W20"
			(at 0.8382 -0.67818 180)
			(unlocked yes)
			(layer "B.SilkS")
			(effects
				(font
					(size 0.4064 0.254)
					(thickness 0.1524)
				)
				(justify left mirror)
			)
		)
		(property "Value" ""
			(at 0 0 0)
			(layer "B.Fab")
			(effects
				(font
					(size 1.27 1.27)
				)
				(justify mirror)
			)
		)
		(duplicate_pad_numbers_are_jumpers no)
		(fp_poly
			(pts
				(xy 0.2794 -0.1016) (xy -0.2794 -0.1016) (xy -0.2794 0.9906) (xy 0.2794 0.9906)
			)
			(stroke
				(width 0)
				(type default)
			)
			(fill no)
			(layer "B.CrtYd")
		)
		(fp_line
			(start 0.2794 0.9906)
			(end -0.2794 0.9906)
			(stroke
				(width 0.1)
				(type default)
			)
			(layer "B.Fab")
		)
		(fp_line
			(start 0.2794 -0.1016)
			(end 0.2794 0.9906)
			(stroke
				(width 0.1)
				(type default)
			)
			(layer "B.Fab")
		)
		(fp_line
			(start -0.2794 0.9906)
			(end -0.2794 -0.1016)
			(stroke
				(width 0.1)
				(type default)
			)
			(layer "B.Fab")
		)
		(fp_line
			(start -0.2794 -0.1016)
			(end 0.2794 -0.1016)
			(stroke
				(width 0.1)
				(type default)
			)
			(layer "B.Fab")
		)
		(pad "1" smd rect
			(at 0 0)
			(size 0.508 0.508)
			(layers "B.Cu" "B.Mask" "B.Paste")
			(net "P3V3_STBY")
		)
		(pad "2" smd rect
			(at 0 0.889)
			(size 0.508 0.508)
			(layers "B.Cu" "B.Mask" "B.Paste")
			(net "FM_POST_CARD_PRES_BMC_R1_N")
		)
		(zone
			(layer "B.Cu")
			(hatch none 0.5)
			(connect_pads
				(clearance 0)
			)
			(min_thickness 0.25)
			(keepout
				(tracks not_allowed)
				(vias allowed)
				(pads allowed)
				(copperpour not_allowed)
				(footprints allowed)
			)
			(placement
				(enabled no)
				(sheetname "")
			)
			(fill
				(thermal_gap 0.5)
				(thermal_bridge_width 0.5)
				(island_removal_mode 0)
			)
			(polygon
				(pts
					(xy 399.637758 -116.952014) (xy 400.145758 -116.952014) (xy 400.145758 -116.571014) (xy 399.637758 -116.571014)
				)
			)
		)
		(zone
			(layer "B.Cu")
			(hatch none 0.5)
			(connect_pads
				(clearance 0)
			)
			(min_thickness 0.25)
			(keepout
				(tracks allowed)
				(vias not_allowed)
				(pads allowed)
				(copperpour not_allowed)
				(footprints allowed)
			)
			(placement
				(enabled no)
				(sheetname "")
			)
			(fill
				(thermal_gap 0.5)
				(thermal_bridge_width 0.5)
				(island_removal_mode 0)
			)
			(polygon
				(pts
					(xy 399.637758 -116.571014) (xy 400.145758 -116.571014) (xy 400.145758 -116.952014) (xy 399.637758 -116.952014)
				)
			)
		)
	)
)
